FILE_TYPE = CONNECTIVITY;
{Allegro Design Entry HDL 16.6-p007 (v16-6-112F) 10/10/2012}
"PAGE_NUMBER" = 152;
0"NC";
1"P3V3\g";
2"PVCCIO_CPU0\g";
3"GND\g";
4"GND\g";
5"GND\g";
6"GND\g";
7"P3V3\g";
8"PVCCIO_CPU0\g";
9"PVCCIO_CPU1\g";
10"PVCCIO_CPU0\g";
11"PVCCIO_CPU1\g";
12"H_CPU1_MEMGHJ_MEMHOT_LVT3_N";
13"H_CPU0_MEMDEF_MEMHOT_G_PCH_N";
14"H_CPU1_MEMKLM_MEMHOT_G_PCH_N";
15"H_CPU1_MEMGHJ_MEMHOT_G_PCH_N";
16"P0V7_GTL2014_2"VOLTAGE"+0.7";
17"H_CPU1_MEMKLM_MEMHOT_G_R_N";
18"H_CPU1_MEMGHJ_MEMHOT_G_R_N";
19"H_CPU0_MEMDEF_MEMHOT_G_R_N";
20"H_CPU0_MEMABC_MEMHOT_G_R_N";
21"H_CPU0_MEMABC_MEMHOT_G_N";
22"H_CPU0_MEMDEF_MEMHOT_G_N";
23"P0V7_GTL2014_2";
24"PD_DIR_2";
25"H_CPU0_MEMABC_MEMHOT_LVT3_N";
26"H_CPU0_MEMABC_MEMHOT_PCH_N";
27"H_CPU0_MEMDEF_MEMHOT_LVT3_BMC_N";
28"H_CPU0_MEMDEF_MEMHOT_PCH_N";
29"H_CPU1_MEMKLM_MEMHOT_LVT3_BMC_N";
30"H_CPU1_MEMGHJ_MEMHOT_LVT3_BMC_N";
31"H_CPU1_MEMGHJ_MEMHOT_PCH_N";
32"H_CPU1_MEMKLM_MEMHOT_LVT3_N";
33"H_CPU0_MEMABC_MEMHOT_LVT3_BMC_N";
34"H_CPU0_DEF_MEMHOT_LVT3_R_N";
35"H_CPU1_KLM_MEMHOT_LVT3_R_N";
36"H_CPU1_MEMGHJ_MEMHOT_LVT3_K_N";
37"H_CPU1_MEMKLM_MEMHOT_LVT3_K_N";
38"H_CPU1_MEMKLM_MEMHOT_LVT3_N";
39"H_CPU0_MEMDEF_MEMHOT_LVT3_K_N";
40"H_CPU0_MEMABC_MEMHOT_LVT3_K_N";
41"H_CPU0_MEMDEF_MEMHOT_LVT3_N";
42"H_CPU0_MEMABC_MEMHOT_LVT3_N";
43"H_CPU1_MEMGHJ_MEMHOT_LVT3_N";
44"H_CPU1_MEMKLM_MEMHOT_PCH_N";
45"H_CPU0_MEMDEF_MEMHOT_LVT3_N";
46"H_CPU1_MEMGHJ_MEMHOT_G_N";
47"H_CPU1_MEMKLM_MEMHOT_G_N";
48"H_CPU0_MEMABC_MEMHOT_G_PCH_N";
49"H_CPU1_GHJ_MEMHOT_LVT3_R_N";
50"H_CPU0_ABC_MEMHOT_LVT3_R_N";
%"GTL2014"
"1","(-5400,4050)","2","mstr_digital","I1";
;
CDS_SEC"1"
LOCATION"U9G1"
MATERIAL"IC"
PART_NUMBER"D66151-001"
SEC"1"
BOM_COST"PROC_SIDEBAND"
SEC_TYPE"SM"
PACK_TYPE"SM"
ROOM"PROC_SIDEBAND"
CDS_LOCATION"U9G1"
CDS_LIB"mstr_digital";
"A0"
$PN"13"35;
"A1"
$PN"12"49;
"A3"
$PN"9"50;
"A2"
$PN"10"34;
"B2"
$PN"5"19;
"B3"
$PN"6"20;
"B0"
$PN"2"17;
"B1"
$PN"3"18;
"GND<1>"
$PN"8"3;
"GND<2>"
$PN"11"3;
"GND<0>"
$PN"7"3;
"VCC"
$PN"14"7;
"VREF"
$PN"4"23;
"DIR"
$PN"1"24;
%"RES"
"1","(-6700,1400)","0","mstr_discrete","I100";
;
CDS_SEC"1"
CDS_LOCATION"R3P63"
WATTAGE"1/16W"
VALUE"0.0"
LOCATION"R3P63"
PART_NUMBER"G21497-005"
PACK_TYPE"0402"
MATERIAL"EMPTY"
TOLERANCE"5%"
SEC_TYPE"0402"
SEC"1"
CDS_LIB"mstr_discrete";
"B"
$PN"2"31;
"A"
$PN"1"12;
%"RES"
"1","(-6700,975)","0","mstr_discrete","I102";
;
CDS_SEC"1"
CDS_LOCATION"R2U45"
PACK_TYPE"0402"
MATERIAL"EMPTY"
PART_NUMBER"G21497-005"
LOCATION"R2U45"
TOLERANCE"5%"
VALUE"0.0"
WATTAGE"1/16W"
SEC_TYPE"0402"
SEC"1"
CDS_LIB"mstr_discrete";
"B"
$PN"2"44;
"A"
$PN"1"32;
%"P3V3"
"1","(-2550,2300)","0","mstr_symbols","I103";
;
HDL_POWER"P3V3"
BODY_TYPE"PLUMBING"
SIZE"1B"
CDS_LIB"mstr_symbols"
VOLTAGE"3.3V";
"G\NAC"1;
%"PVCCIO_CPU0"
"1","(-3100,2300)","0","mstr_symbols","I104";
;
HDL_POWER"PVCCIO_CPU0"
BODY_TYPE"PLUMBING"
VOLTAGE"1.1V"
CDS_LIB"mstr_symbols";
"G\NAC"2;
%"RES"
"2","(-3100,2075)","0","mstr_discrete","I105";
;
PACK_TYPE"0402"
PART_NUMBER"G21796-047"
LOCATION"R1W35"
VALUE"49.9"
TOLERANCE"1%"
WATTAGE"1/16W"
MATERIAL"EMPTY"
CDS_SEC"1"
SEC_TYPE"0402"
SEC"1"
ROOM"SB"
CDS_LIB"mstr_discrete"
CDS_LOCATION"R1W35";
"A"
$PN"1"2;
"B"
$PN"2"16;
%"374R2F-1-GP"
"1","(-2550,2075)","0","w_hdl","I106";
;
CDS_SEC"1"
$SEC"1"
CDS_LOCATION"R1U43"
PACK_SIZE"0402"
LOCATION"R1U43"
VALUE"374R2F-1-GP"
ATTRIBUTE"374 OHM"
TOLERANCE"1%"
RATED"1/16W"
CDS_LMAN_SYM_OUTLINE"-50,75,50,-75"
CDS_LIB"w_hdl"
PART_NUMBER"64.37405.6DL"
PACK_TYPE"SMD-RG";
"2"
$PN"2"16;
"1"
$PN"1"1;
%"RES"
"1","(-2400,4075)","0","mstr_discrete","I14";
;
CDS_SEC"1"
CDS_LOCATION"R9G31"
PART_NUMBER"G21796-074"
LOCATION"R9G31"
TOLERANCE"1%"
VALUE"33.2"
WATTAGE"1/16W"
PACK_TYPE"0402"
MATERIAL"CHIP"
CDS_LIB"mstr_discrete"
ROOM"PROC_SIDEBAND"
SEC_TYPE"0402"
BOM_COST"PROC_SIDEBAND"
SEC"1";
"B"
$PN"2"41;
"A"
$PN"1"39;
%"RES"
"1","(-2400,3900)","0","mstr_discrete","I15";
;
CDS_SEC"1"
VALUE"33.2"
TOLERANCE"1%"
MATERIAL"CHIP"
LOCATION"R1U36"
PACK_TYPE"0402"
PART_NUMBER"G21796-074"
WATTAGE"1/16W"
CDS_LIB"mstr_discrete"
CDS_LOCATION"R1U36"
ROOM"PROC_SIDEBAND"
BOM_COST"PROC_SIDEBAND"
SEC_TYPE"0402"
SEC"1";
"B"
$PN"2"43;
"A"
$PN"1"36;
%"RES"
"1","(-2400,3725)","0","mstr_discrete","I16";
;
CDS_SEC"1"
VALUE"33.2"
TOLERANCE"1%"
WATTAGE"1/16W"
PART_NUMBER"G21796-074"
PACK_TYPE"0402"
LOCATION"R1U34"
MATERIAL"CHIP"
CDS_LIB"mstr_discrete"
CDS_LOCATION"R1U34"
ROOM"PROC_TRANSLATORS"
SEC_TYPE"0402"
BOM_COST"PROC_SIDEBAND"
SEC"1";
"B"
$PN"2"38;
"A"
$PN"1"37;
%"GND"
"1","(-5900,3525)","0","mstr_symbols","I17";
;
VOLTAGE"0.0V"
CDS_LIB"mstr_symbols"
SIZE"1B"
BODY_TYPE"PLUMBING"
HDL_POWER"GND";
"A\NAC"3;
%"CAP"
"1","(-4525,4650)","0","mstr_discrete","I18";
;
CDS_SEC"1"
VALUE"1.0UF"
LOCATION"C1U19"
VOLTAGE"16V"
PACK_TYPE"0402"
MATERIAL"X6S"
PART_NUMBER"D97712-011"
TOLERANCE"10%"
SEC_TYPE"0402"
BOM_COST"PROC_SIDEBAND"
SEC"1"
CDS_LIB"mstr_discrete"
CDS_LOCATION"C1U19"
ROOM"PROC_SIDEBAND";
"A"
$PN"1"7;
"B"
$PN"2"4;
%"RES"
"1","(-4350,4200)","0","mstr_discrete","I2";
;
CDS_SEC"1"
MATERIAL"CHIP"
PART_NUMBER"G21796-026"
PACK_TYPE"0402"
WATTAGE"1/16W"
TOLERANCE"1%"
LOCATION"R1U30"
VALUE"1.00K"
CDS_LIB"mstr_discrete"
SEC"1"
SEC_TYPE"0402"
BOM_COST"PROC_SIDEBAND"
CDS_LOCATION"R1U30"
ROOM"PROC_TRANSLATORS";
"B"
$PN"2"6;
"A"
$PN"1"24;
%"GND"
"1","(-4525,4450)","0","mstr_symbols","I20";
;
SIZE"1B"
CDS_LIB"mstr_symbols"
VOLTAGE"0.0V"
BODY_TYPE"PLUMBING"
HDL_POWER"GND";
"A\NAC"4;
%"RES"
"2","(-2550,1600)","0","mstr_discrete","I26";
;
CDS_SEC"1"
MATERIAL"CHIP"
PACK_TYPE"0402"
LOCATION"R1U37"
VALUE"100.0"
TOLERANCE"1%"
WATTAGE"1/16W"
PART_NUMBER"G21796-017"
SEC_TYPE"0402"
SEC"1"
BOM_COST"PROC_SIDEBAND"
ROOM"PROC_SIDEBAND"
CDS_LOCATION"R1U37"
CDS_LIB"mstr_discrete";
"A"
$PN"1"16;
"B"
$PN"2"5;
%"CAP_A"
"1","(-2925,1600)","0","dev_discrete","I27";
;
CDS_SEC"1"
PART_NUMBER"A36096-030"
TOLERANCE"10%"
MATERIAL"X7R"
LOCATION"C1U22"
PACK_TYPE"0402V"
VALUE"0.1UF"
VOLTAGE"16V"
SEC_TYPE"0402V"
SEC"1"
BOM_COST"PROC_SIDEBAND"
ROOM"PROC_SIDEBAND"
CDS_LOCATION"C1U22"
CDS_LIB"dev_discrete";
"B"
$PN"2"5;
"A"
$PN"1"16;
%"GND"
"1","(-2550,1275)","0","mstr_symbols","I29";
;
CDS_LIB"mstr_symbols"
SIZE"1B"
VOLTAGE"0.0V"
BODY_TYPE"PLUMBING"
HDL_POWER"GND";
"A\NAC"5;
%"GND"
"1","(-3825,4125)","0","mstr_symbols","I3";
;
CDS_LIB"mstr_symbols"
VOLTAGE"0.0V"
SIZE"1B"
BODY_TYPE"PLUMBING"
HDL_POWER"GND";
"A\NAC"6;
%"RES"
"1","(-6950,4225)","0","mstr_discrete","I45";
;
CDS_SEC"1"
CDS_LOCATION"R9G34"
VALUE"0.0"
LOCATION"R9G34"
TOLERANCE"5%"
PART_NUMBER"G21497-005"
MATERIAL"CHIP"
WATTAGE"1/16W"
PACK_TYPE"0402"
SEC_TYPE"0402"
SEC"1"
CDS_LIB"mstr_discrete";
"B"
$PN"2"20;
"A"
$PN"1"21;
%"RES"
"2","(-3150,4600)","0","mstr_discrete","I47";
;
CDS_SEC"1"
CDS_LOCATION"R9G27"
MATERIAL"EMPTY"
LOCATION"R9G27"
PART_NUMBER"G21497-005"
VALUE"0.0"
TOLERANCE"5%"
PACK_TYPE"0402"
WATTAGE"1/16W"
SEC_TYPE"0402"
SEC"1"
CDS_LIB"mstr_discrete";
"A"
$PN"1"13;
"B"
$PN"2"39;
%"RES"
"1","(-6950,4050)","0","mstr_discrete","I49";
;
CDS_SEC"1"
CDS_LOCATION"R1U58"
VALUE"0.0"
LOCATION"R1U58"
TOLERANCE"5%"
PART_NUMBER"G21497-005"
MATERIAL"CHIP"
PACK_TYPE"0402"
WATTAGE"1/16W"
SEC_TYPE"0402"
SEC"1"
CDS_LIB"mstr_discrete";
"B"
$PN"2"19;
"A"
$PN"1"22;
%"P3V3"
"1","(-4775,4925)","0","mstr_symbols","I5";
;
HDL_POWER"P3V3"
BODY_TYPE"PLUMBING"
SIZE"1B"
CDS_LIB"mstr_symbols"
VOLTAGE"3.3V";
"G\NAC"7;
%"RES"
"2","(-7175,4525)","0","mstr_discrete","I50";
;
CDS_SEC"1"
CDS_LOCATION"R1U56"
LOCATION"R1U56"
VALUE"0.0"
MATERIAL"EMPTY"
WATTAGE"1/16W"
PACK_TYPE"0402"
PART_NUMBER"G21497-005"
TOLERANCE"5%"
SEC_TYPE"0402"
SEC"1"
CDS_LIB"mstr_discrete";
"A"
$PN"1"13;
"B"
$PN"2"22;
%"RES"
"2","(-7450,4525)","0","mstr_discrete","I51";
;
CDS_SEC"1"
CDS_LOCATION"R2U51"
LOCATION"R2U51"
VALUE"0.0"
MATERIAL"EMPTY"
WATTAGE"1/16W"
TOLERANCE"5%"
PACK_TYPE"0402"
PART_NUMBER"G21497-005"
SEC"1"
SEC_TYPE"0402"
CDS_LIB"mstr_discrete";
"A"
$PN"1"48;
"B"
$PN"2"21;
%"PVCCIO_CPU0"
"1","(-7925,4950)","0","mstr_symbols","I52";
;
CDS_LIB"mstr_symbols"
VOLTAGE"1.1V"
BODY_TYPE"PLUMBING"
HDL_POWER"PVCCIO_CPU0";
"G\NAC"8;
%"RES"
"2","(-7875,4650)","0","mstr_discrete","I53";
;
CDS_SEC"1"
WATTAGE"1/16W"
TOLERANCE"1%"
LOCATION"R2U40"
VALUE"150.0"
PACK_TYPE"0402"
MATERIAL"CHIP"
PART_NUMBER"G21796-009"
SEC"1"
SEC_TYPE"0402"
CDS_LOCATION"R2U40"
CDS_LIB"mstr_discrete"
BOM_COST"PROC_SIDEBAND"
ROOM"PROC_SIDEBAND";
"A"
$PN"1"8;
"B"
$PN"2"21;
%"RES"
"2","(-7975,4650)","2","mstr_discrete","I54";
;
CDS_SEC"1"
LOCATION"R2U41"
VALUE"150.0"
WATTAGE"1/16W"
PACK_TYPE"0402"
MATERIAL"CHIP"
PART_NUMBER"G21796-009"
TOLERANCE"1%"
SEC"1"
SEC_TYPE"0402"
CDS_LOCATION"R2U41"
CDS_LIB"mstr_discrete"
BOM_COST"PROC_SIDEBAND"
ROOM"PROC_SIDEBAND";
"A"
$PN"1"8;
"B"
$PN"2"22;
%"PVCCIO_CPU1"
"1","(-8375,4950)","0","mstr_symbols","I55";
;
VOLTAGE"1.1V"
CDS_LIB"mstr_symbols"
BODY_TYPE"PLUMBING"
HDL_POWER"PVCCIO_CPU1";
"G\NAC"9;
%"RES"
"2","(-8325,4650)","0","mstr_discrete","I56";
;
CDS_SEC"1"
LOCATION"R1U41"
PACK_TYPE"0402"
MATERIAL"CHIP"
TOLERANCE"1%"
WATTAGE"1/16W"
VALUE"150.0"
SEC_TYPE"0402"
SEC"1"
CDS_LOCATION"R1U41"
CDS_LIB"mstr_discrete"
BOM_COST"PROC_SIDEBAND"
PART_NUMBER"G21796-009"
ROOM"PROC_SIDEBAND";
"A"
$PN"1"9;
"B"
$PN"2"46;
%"RES"
"2","(-8425,4650)","2","mstr_discrete","I57";
;
CDS_SEC"1"
PACK_TYPE"0402"
PART_NUMBER"G21796-009"
MATERIAL"CHIP"
LOCATION"R1U35"
TOLERANCE"1%"
WATTAGE"1/16W"
VALUE"150.0"
BOM_COST"PROC_SIDEBAND"
CDS_LIB"mstr_discrete"
SEC_TYPE"0402"
SEC"1"
CDS_LOCATION"R1U35"
ROOM"PROC_SIDEBAND";
"A"
$PN"1"9;
"B"
$PN"2"47;
%"RES"
"2","(-7800,3250)","0","mstr_discrete","I58";
;
CDS_SEC"1"
LOCATION"R4P17"
MATERIAL"CHIP"
WATTAGE"1/16W"
TOLERANCE"1%"
PART_NUMBER"G21796-009"
PACK_TYPE"0402"
VALUE"150.0"
SEC_TYPE"0402"
SEC"1"
CDS_LOCATION"R4P17"
CDS_LIB"mstr_discrete"
BOM_COST"PROC_SIDEBAND"
ROOM"PROC_SIDEBAND";
"A"
$PN"1"21;
"B"
$PN"2"10;
%"RES"
"2","(-7900,3250)","2","mstr_discrete","I59";
;
CDS_SEC"1"
PART_NUMBER"G21796-009"
PACK_TYPE"0402"
WATTAGE"1/16W"
LOCATION"R4P20"
TOLERANCE"1%"
VALUE"150.0"
MATERIAL"CHIP"
CDS_LOCATION"R4P20"
BOM_COST"PROC_SIDEBAND"
CDS_LIB"mstr_discrete"
SEC_TYPE"0402"
SEC"1"
ROOM"PROC_SIDEBAND";
"A"
$PN"1"22;
"B"
$PN"2"10;
%"RES"
"1","(-2400,4250)","0","mstr_discrete","I6";
;
CDS_SEC"1"
PART_NUMBER"G21796-074"
WATTAGE"1/16W"
VALUE"33.2"
LOCATION"R1U46"
TOLERANCE"1%"
MATERIAL"CHIP"
PACK_TYPE"0402"
CDS_LOCATION"R1U46"
CDS_LIB"mstr_discrete"
ROOM"PROC_SIDEBAND"
SEC_TYPE"0402"
BOM_COST"PROC_SIDEBAND"
SEC"1";
"B"
$PN"2"42;
"A"
$PN"1"40;
%"PVCCIO_CPU0"
"1","(-7850,2925)","6","mstr_symbols","I60";
;
VOLTAGE"1.1V"
CDS_LIB"mstr_symbols"
BODY_TYPE"PLUMBING"
HDL_POWER"PVCCIO_CPU0";
"G\NAC"10;
%"RES"
"2","(-8250,3275)","0","mstr_discrete","I61";
;
CDS_SEC"1"
PACK_TYPE"0402"
PART_NUMBER"G21796-009"
VALUE"150.0"
TOLERANCE"1%"
MATERIAL"CHIP"
WATTAGE"1/16W"
LOCATION"R7P5"
SEC_TYPE"0402"
SEC"1"
CDS_LOCATION"R7P5"
CDS_LIB"mstr_discrete"
BOM_COST"PROC_SIDEBAND"
ROOM"PROC_SIDEBAND";
"A"
$PN"1"46;
"B"
$PN"2"11;
%"RES"
"2","(-8350,3275)","2","mstr_discrete","I62";
;
CDS_SEC"1"
LOCATION"R7P21"
PART_NUMBER"G21796-009"
VALUE"150.0"
TOLERANCE"1%"
PACK_TYPE"0402"
MATERIAL"CHIP"
WATTAGE"1/16W"
SEC_TYPE"0402"
SEC"1"
CDS_LOCATION"R7P21"
CDS_LIB"mstr_discrete"
BOM_COST"PROC_SIDEBAND"
ROOM"PROC_SIDEBAND";
"A"
$PN"1"47;
"B"
$PN"2"11;
%"PVCCIO_CPU1"
"1","(-8300,2925)","6","mstr_symbols","I63";
;
CDS_LIB"mstr_symbols"
VOLTAGE"1.1V"
BODY_TYPE"PLUMBING"
HDL_POWER"PVCCIO_CPU1";
"G\NAC"11;
%"RES"
"1","(-6950,3900)","0","mstr_discrete","I64";
;
CDS_SEC"1"
CDS_LOCATION"R1U53"
VALUE"0.0"
LOCATION"R1U53"
MATERIAL"CHIP"
PART_NUMBER"G21497-005"
WATTAGE"1/16W"
PACK_TYPE"0402"
TOLERANCE"5%"
SEC_TYPE"0402"
SEC"1"
CDS_LIB"mstr_discrete";
"B"
$PN"2"18;
"A"
$PN"1"46;
%"RES"
"1","(-6950,3750)","0","mstr_discrete","I65";
;
CDS_SEC"1"
CDS_LOCATION"R1U60"
VALUE"0.0"
LOCATION"R1U60"
PART_NUMBER"G21497-005"
TOLERANCE"5%"
WATTAGE"1/16W"
MATERIAL"CHIP"
PACK_TYPE"0402"
SEC"1"
SEC_TYPE"0402"
CDS_LIB"mstr_discrete";
"B"
$PN"2"17;
"A"
$PN"1"47;
%"RES"
"2","(-2850,4600)","0","mstr_discrete","I66";
;
CDS_SEC"1"
CDS_LOCATION"R2U49"
LOCATION"R2U49"
VALUE"0.0"
TOLERANCE"5%"
MATERIAL"EMPTY"
WATTAGE"1/16W"
PACK_TYPE"0402"
PART_NUMBER"G21497-005"
SEC_TYPE"0402"
SEC"1"
CDS_LIB"mstr_discrete";
"A"
$PN"1"48;
"B"
$PN"2"40;
%"RES"
"2","(-7175,3500)","0","mstr_discrete","I67";
;
CDS_SEC"1"
CDS_LOCATION"R1U55"
MATERIAL"EMPTY"
PACK_TYPE"0402"
PART_NUMBER"G21497-005"
WATTAGE"1/16W"
TOLERANCE"5%"
VALUE"0.0"
LOCATION"R1U55"
SEC"1"
SEC_TYPE"0402"
CDS_LIB"mstr_discrete";
"A"
$PN"1"46;
"B"
$PN"2"15;
%"RES"
"2","(-7450,3500)","0","mstr_discrete","I68";
;
CDS_SEC"1"
CDS_LOCATION"R1U62"
LOCATION"R1U62"
VALUE"0.0"
MATERIAL"EMPTY"
WATTAGE"1/16W"
TOLERANCE"5%"
PACK_TYPE"0402"
PART_NUMBER"G21497-005"
SEC_TYPE"0402"
SEC"1"
CDS_LIB"mstr_discrete";
"A"
$PN"1"47;
"B"
$PN"2"14;
%"RES"
"2","(-3175,3425)","0","mstr_discrete","I69";
;
CDS_SEC"1"
CDS_LOCATION"R1U57"
PACK_TYPE"0402"
MATERIAL"EMPTY"
LOCATION"R1U57"
VALUE"0.0"
TOLERANCE"5%"
WATTAGE"1/16W"
PART_NUMBER"G21497-005"
SEC"1"
SEC_TYPE"0402"
CDS_LIB"mstr_discrete";
"A"
$PN"1"36;
"B"
$PN"2"15;
%"RES"
"2","(-2875,3425)","0","mstr_discrete","I70";
;
CDS_SEC"1"
CDS_LOCATION"R1U61"
VALUE"0.0"
TOLERANCE"5%"
WATTAGE"1/16W"
PART_NUMBER"G21497-005"
MATERIAL"EMPTY"
LOCATION"R1U61"
PACK_TYPE"0402"
SEC_TYPE"0402"
SEC"1"
CDS_LIB"mstr_discrete";
"A"
$PN"1"37;
"B"
$PN"2"14;
%"RES"
"1","(-3375,3725)","0","mstr_discrete","I71";
;
CDS_SEC"1"
CDS_LOCATION"R9G28"
VALUE"0.0"
PACK_TYPE"0402"
WATTAGE"1/16W"
TOLERANCE"5%"
PART_NUMBER"G21497-005"
LOCATION"R9G28"
MATERIAL"CHIP"
SEC_TYPE"0402"
SEC"1"
CDS_LIB"mstr_discrete";
"B"
$PN"2"37;
"A"
$PN"1"35;
%"RES"
"1","(-3375,3900)","0","mstr_discrete","I72";
;
CDS_SEC"1"
CDS_LOCATION"R9G32"
PART_NUMBER"G21497-005"
WATTAGE"1/16W"
TOLERANCE"5%"
PACK_TYPE"0402"
VALUE"0.0"
LOCATION"R9G32"
MATERIAL"CHIP"
SEC"1"
SEC_TYPE"0402"
CDS_LIB"mstr_discrete";
"B"
$PN"2"36;
"A"
$PN"1"49;
%"RES"
"1","(-3375,4075)","0","mstr_discrete","I73";
;
CDS_SEC"1"
CDS_LOCATION"R9G33"
VALUE"0.0"
LOCATION"R9G33"
TOLERANCE"5%"
PACK_TYPE"0402"
WATTAGE"1/16W"
MATERIAL"CHIP"
PART_NUMBER"G21497-005"
SEC"1"
SEC_TYPE"0402"
CDS_LIB"mstr_discrete";
"B"
$PN"2"39;
"A"
$PN"1"34;
%"RES"
"1","(-3375,4250)","0","mstr_discrete","I74";
;
CDS_SEC"1"
CDS_LOCATION"R1U59"
WATTAGE"1/16W"
MATERIAL"CHIP"
TOLERANCE"5%"
PACK_TYPE"0402"
VALUE"0.0"
LOCATION"R1U59"
PART_NUMBER"G21497-005"
SEC"1"
SEC_TYPE"0402"
CDS_LIB"mstr_discrete";
"B"
$PN"2"40;
"A"
$PN"1"50;
%"RES"
"1","(-6700,2475)","0","mstr_discrete","I79";
;
CDS_SEC"1"
CDS_LOCATION"R2U47"
PART_NUMBER"G21497-005"
LOCATION"R2U47"
MATERIAL"CHIP"
PACK_TYPE"0402"
VALUE"0.0"
WATTAGE"1/16W"
TOLERANCE"5%"
SEC_TYPE"0402"
SEC"1"
CDS_LIB"mstr_discrete";
"B"
$PN"2"33;
"A"
$PN"1"25;
%"RES"
"1","(-6700,2025)","0","mstr_discrete","I92";
;
CDS_SEC"1"
CDS_LOCATION"R9G29"
PACK_TYPE"0402"
LOCATION"R9G29"
PART_NUMBER"G21497-005"
MATERIAL"CHIP"
TOLERANCE"5%"
WATTAGE"1/16W"
VALUE"0.0"
SEC_TYPE"0402"
SEC"1"
CDS_LIB"mstr_discrete";
"B"
$PN"2"27;
"A"
$PN"1"45;
%"RES"
"1","(-6700,1600)","0","mstr_discrete","I93";
;
CDS_SEC"1"
CDS_LOCATION"R1U54"
PACK_TYPE"0402"
MATERIAL"CHIP"
TOLERANCE"5%"
WATTAGE"1/16W"
PART_NUMBER"G21497-005"
LOCATION"R1U54"
VALUE"0.0"
SEC_TYPE"0402"
SEC"1"
CDS_LIB"mstr_discrete";
"B"
$PN"2"30;
"A"
$PN"1"12;
%"RES"
"1","(-6700,1175)","0","mstr_discrete","I94";
;
CDS_SEC"1"
CDS_LOCATION"R2U46"
WATTAGE"1/16W"
PART_NUMBER"G21497-005"
PACK_TYPE"0402"
LOCATION"R2U46"
TOLERANCE"5%"
MATERIAL"CHIP"
VALUE"0.0"
SEC_TYPE"0402"
SEC"1"
CDS_LIB"mstr_discrete";
"B"
$PN"2"29;
"A"
$PN"1"32;
%"RES"
"1","(-6700,2275)","0","mstr_discrete","I95";
;
CDS_SEC"1"
CDS_LOCATION"R3N30"
PART_NUMBER"G21497-005"
PACK_TYPE"0402"
LOCATION"R3N30"
MATERIAL"EMPTY"
WATTAGE"1/16W"
TOLERANCE"5%"
VALUE"0.0"
SEC_TYPE"0402"
SEC"1"
CDS_LIB"mstr_discrete";
"B"
$PN"2"26;
"A"
$PN"1"25;
%"RES"
"1","(-6700,1825)","0","mstr_discrete","I98";
;
CDS_SEC"1"
CDS_LOCATION"R9G30"
PACK_TYPE"0402"
MATERIAL"EMPTY"
TOLERANCE"5%"
WATTAGE"1/16W"
LOCATION"R9G30"
PART_NUMBER"G21497-005"
VALUE"0.0"
SEC_TYPE"0402"
SEC"1"
CDS_LIB"mstr_discrete";
"B"
$PN"2"28;
"A"
$PN"1"45;
END.
